(kicad_pcb
	(version 20241229)
	(generator "pcbnew")
	(generator_version "9.0")
	(general
		(thickness 1.711)
		(legacy_teardrops no)
	)
	(paper "A4")
	(title_block
		(title "Antmicro Baseboard for Jetson AGX Thor")
		(date "2026-02-18")
		(rev "1.1.0")
		(company "Antmicro Ltd")
		(comment 1 "www.antmicro.com")
		(comment 9 "footprints 961-966 of 1170")
	)
	(layers
		(0 "F.Cu" signal)
		(4 "In1.Cu" signal)
		(6 "In2.Cu" signal)
		(8 "In3.Cu" signal)
		(10 "In4.Cu" jumper)
		(12 "In5.Cu" signal)
		(14 "In6.Cu" signal)
		(16 "In7.Cu" signal)
		(18 "In8.Cu" signal)
		(2 "B.Cu" signal)
		(9 "F.Adhes" user "F.Adhesive")
		(11 "B.Adhes" user "B.Adhesive")
		(13 "F.Paste" user)
		(15 "B.Paste" user)
		(5 "F.SilkS" user "F.Silkscreen")
		(7 "B.SilkS" user "B.Silkscreen")
		(1 "F.Mask" user)
		(3 "B.Mask" user)
		(17 "Dwgs.User" user "User.Drawings")
		(19 "Cmts.User" user "User.Comments")
		(21 "Eco1.User" user "User.Eco1")
		(23 "Eco2.User" user "User.Eco2")
		(25 "Edge.Cuts" user)
		(27 "Margin" user)
		(31 "F.CrtYd" user "F.Courtyard")
		(29 "B.CrtYd" user "B.Courtyard")
		(35 "F.Fab" user)
		(33 "B.Fab" user)
	)
	(footprint "antmicro-footprints:R_0402_1005Metric"
		(layer "B.Cu")
		(at 158.51 62.77 90)
		(descr "Resistor SMD 0402")
		(tags "resistor SMD 0402")
		(property "Reference" "R285"
			(at -7.13 -7.01 90)
			(layer "B.SilkS")
			(effects
				(font
					(size 0.7 0.7)
					(thickness 0.15)
				)
				(justify right top mirror)
			)
		)
		(property "Value" "R_10k_0402"
			(at -1.011843 -1.772047 90)
			(layer "B.Fab")
			(effects
				(font
					(size 0.7 0.7)
					(thickness 0.15)
				)
				(justify right top mirror)
			)
		)
		(property "Datasheet" "https://www.bourns.com/docs/product-datasheets/cr.pdf"
			(at 0 0 90)
			(layer "B.Fab")
			(hide yes)
			(effects
				(font
					(size 1.27 1.27)
					(thickness 0.15)
				)
				(justify mirror)
			)
		)
		(property "Description" "SMD Chip Resistor, 10 kohm, ± 1%, 62.5 mW, 0402 [1005 Metric], Thick Film, General Purpose"
			(at 0 0 90)
			(layer "B.Fab")
			(hide yes)
			(effects
				(font
					(size 1.27 1.27)
					(thickness 0.15)
				)
				(justify mirror)
			)
		)
		(property "MPN" "CR0402-FX-1002GLF"
			(at 0 0 270)
			(unlocked yes)
			(layer "B.Fab")
			(hide yes)
			(effects
				(font
					(size 1 1)
					(thickness 0.15)
				)
				(justify mirror)
			)
		)
		(property "Manufacturer" "Bourns"
			(at 0 0 270)
			(unlocked yes)
			(layer "B.Fab")
			(hide yes)
			(effects
				(font
					(size 1 1)
					(thickness 0.15)
				)
				(justify mirror)
			)
		)
		(property "License" "Apache-2.0"
			(at 0 0 270)
			(unlocked yes)
			(layer "B.Fab")
			(hide yes)
			(effects
				(font
					(size 1 1)
					(thickness 0.15)
				)
				(justify mirror)
			)
		)
		(property "Author" "Antmicro"
			(at 0 0 270)
			(unlocked yes)
			(layer "B.Fab")
			(hide yes)
			(effects
				(font
					(size 1 1)
					(thickness 0.15)
				)
				(justify mirror)
			)
		)
		(property "Val" "10k"
			(at 0 0 270)
			(unlocked yes)
			(layer "B.Fab")
			(hide yes)
			(effects
				(font
					(size 1 1)
					(thickness 0.15)
				)
				(justify mirror)
			)
		)
		(property "Tolerance" "1%"
			(at 0 0 270)
			(unlocked yes)
			(layer "B.Fab")
			(hide yes)
			(effects
				(font
					(size 1 1)
					(thickness 0.15)
				)
				(justify mirror)
			)
		)
		(sheetname "/SoM_IO2/")
		(sheetfile "som_io2.kicad_sch")
		(attr smd exclude_from_pos_files exclude_from_bom dnp)
		(fp_rect
			(start -0.925 0.47)
			(end 0.925 -0.47)
			(stroke
				(width 0.05)
				(type default)
			)
			(fill no)
			(layer "B.CrtYd")
		)
		(fp_rect
			(start -0.5 0.25)
			(end 0.5 -0.25)
			(stroke
				(width 0.15)
				(type solid)
			)
			(fill no)
			(layer "B.Fab")
		)
		(fp_text user "Author: Antmicro"
			(at -0.95 -4.169 90)
			(layer "B.Fab")
			(effects
				(font
					(size 0.7 0.7)
					(thickness 0.15)
				)
				(justify right top mirror)
			)
		)
		(fp_text user "License: Apache-2.0"
			(at -0.95 -5.169 90)
			(layer "B.Fab")
			(effects
				(font
					(size 0.7 0.7)
					(thickness 0.15)
				)
				(justify right top mirror)
			)
		)
		(fp_text user "${REFERENCE}"
			(at -0.95 -3.168 90)
			(layer "B.Fab")
			(effects
				(font
					(size 0.7 0.7)
					(thickness 0.15)
				)
				(justify right top mirror)
			)
		)
		(pad "1" smd roundrect
			(at -0.48 0 90)
			(size 0.59 0.64)
			(layers "B.Cu" "B.Mask" "B.Paste")
			(roundrect_rratio 0.25)
			(net 627 "/SoM_IO2/JTAG_TRST_N")
			(pintype "passive")
		)
		(pad "2" smd roundrect
			(at 0.48 0 90)
			(size 0.59 0.64)
			(layers "B.Cu" "B.Mask" "B.Paste")
			(roundrect_rratio 0.25)
			(net 11 "+1V8")
			(pintype "passive")
		)
	)
	(footprint "antmicro-footprints:R_0402_1005Metric"
		(layer "B.Cu")
		(at 65.1 70.4 90)
		(descr "Resistor SMD 0402")
		(tags "resistor SMD 0402")
		(property "Reference" "R400"
			(at -2.2 3.7 90)
			(layer "B.SilkS")
			(effects
				(font
					(size 0.7 0.7)
					(thickness 0.15)
				)
				(justify right top mirror)
			)
		)
		(property "Value" "R_0R_0402"
			(at -1.011843 -1.772047 90)
			(layer "B.Fab")
			(effects
				(font
					(size 0.7 0.7)
					(thickness 0.15)
				)
				(justify right top mirror)
			)
		)
		(property "Datasheet" "https://industrial.panasonic.com/cdbs/www-data/pdf/RDA0000/AOA0000C301.pdf"
			(at 0 0 90)
			(layer "B.Fab")
			(hide yes)
			(effects
				(font
					(size 1.27 1.27)
					(thickness 0.15)
				)
				(justify mirror)
			)
		)
		(property "Description" "SMD Chip Resistor, Jumper, 0 ohm, 100 mW, 0402 [1005 Metric], Thick Film, General Purpose"
			(at 0 0 90)
			(layer "B.Fab")
			(hide yes)
			(effects
				(font
					(size 1.27 1.27)
					(thickness 0.15)
				)
				(justify mirror)
			)
		)
		(property "MPN" "ERJ2GE0R00X"
			(at 0 0 270)
			(unlocked yes)
			(layer "B.Fab")
			(hide yes)
			(effects
				(font
					(size 1 1)
					(thickness 0.15)
				)
				(justify mirror)
			)
		)
		(property "Manufacturer" "Panasonic"
			(at 0 0 270)
			(unlocked yes)
			(layer "B.Fab")
			(hide yes)
			(effects
				(font
					(size 1 1)
					(thickness 0.15)
				)
				(justify mirror)
			)
		)
		(property "License" "Apache-2.0"
			(at 0 0 270)
			(unlocked yes)
			(layer "B.Fab")
			(hide yes)
			(effects
				(font
					(size 1 1)
					(thickness 0.15)
				)
				(justify mirror)
			)
		)
		(property "Author" "Antmicro"
			(at 0 0 270)
			(unlocked yes)
			(layer "B.Fab")
			(hide yes)
			(effects
				(font
					(size 1 1)
					(thickness 0.15)
				)
				(justify mirror)
			)
		)
		(property "Val" "0R"
			(at 0 0 270)
			(unlocked yes)
			(layer "B.Fab")
			(hide yes)
			(effects
				(font
					(size 1 1)
					(thickness 0.15)
				)
				(justify mirror)
			)
		)
		(property "Tolerance" "~"
			(at 0 0 270)
			(unlocked yes)
			(layer "B.Fab")
			(hide yes)
			(effects
				(font
					(size 1 1)
					(thickness 0.15)
				)
				(justify mirror)
			)
		)
		(property "Current" "1A"
			(at 0 0 270)
			(unlocked yes)
			(layer "B.Fab")
			(hide yes)
			(effects
				(font
					(size 1 1)
					(thickness 0.15)
				)
				(justify mirror)
			)
		)
		(sheetname "/CSI/")
		(sheetfile "csi.kicad_sch")
		(attr smd)
		(fp_rect
			(start -0.925 0.47)
			(end 0.925 -0.47)
			(stroke
				(width 0.05)
				(type default)
			)
			(fill no)
			(layer "B.CrtYd")
		)
		(fp_rect
			(start -0.5 0.25)
			(end 0.5 -0.25)
			(stroke
				(width 0.15)
				(type solid)
			)
			(fill no)
			(layer "B.Fab")
		)
		(fp_text user "${REFERENCE}"
			(at -0.95 -3.168 90)
			(layer "B.Fab")
			(effects
				(font
					(size 0.7 0.7)
					(thickness 0.15)
				)
				(justify right top mirror)
			)
		)
		(fp_text user "License: Apache-2.0"
			(at -0.95 -5.169 90)
			(layer "B.Fab")
			(effects
				(font
					(size 0.7 0.7)
					(thickness 0.15)
				)
				(justify right top mirror)
			)
		)
		(fp_text user "Author: Antmicro"
			(at -0.95 -4.169 90)
			(layer "B.Fab")
			(effects
				(font
					(size 0.7 0.7)
					(thickness 0.15)
				)
				(justify right top mirror)
			)
		)
		(pad "1" smd roundrect
			(at -0.48 0 90)
			(size 0.59 0.64)
			(layers "B.Cu" "B.Mask" "B.Paste")
			(roundrect_rratio 0.25)
			(net 1375 "Net-(J11-Pad42)")
			(pintype "passive")
		)
		(pad "2" smd roundrect
			(at 0.48 0 90)
			(size 0.59 0.64)
			(layers "B.Cu" "B.Mask" "B.Paste")
			(roundrect_rratio 0.25)
			(net 988 "/CSI/SCL_CAM1")
			(pintype "passive")
		)
	)
	(footprint "antmicro-footprints:R_0402_1005Metric"
		(layer "B.Cu")
		(at 143.6 65.2 90)
		(descr "Resistor SMD 0402")
		(tags "resistor SMD 0402")
		(property "Reference" "R245"
			(at -3.7 -0.4 90)
			(layer "B.SilkS")
			(effects
				(font
					(size 0.7 0.7)
					(thickness 0.15)
				)
				(justify right top mirror)
			)
		)
		(property "Value" "R_10k_0402"
			(at -1.011843 -1.772046 90)
			(layer "B.Fab")
			(effects
				(font
					(size 0.7 0.7)
					(thickness 0.15)
				)
				(justify right top mirror)
			)
		)
		(property "Datasheet" "https://www.bourns.com/docs/product-datasheets/cr.pdf"
			(at 0 0 90)
			(layer "B.Fab")
			(hide yes)
			(effects
				(font
					(size 1.27 1.27)
					(thickness 0.15)
				)
				(justify mirror)
			)
		)
		(property "Description" "SMD Chip Resistor, 10 kohm, ± 1%, 62.5 mW, 0402 [1005 Metric], Thick Film, General Purpose"
			(at 0 0 90)
			(layer "B.Fab")
			(hide yes)
			(effects
				(font
					(size 1.27 1.27)
					(thickness 0.15)
				)
				(justify mirror)
			)
		)
		(property "Manufacturer" "Bourns"
			(at 0 0 270)
			(unlocked yes)
			(layer "B.Fab")
			(hide yes)
			(effects
				(font
					(size 1 1)
					(thickness 0.15)
				)
				(justify mirror)
			)
		)
		(property "MPN" "CR0402-FX-1002GLF"
			(at 0 0 270)
			(unlocked yes)
			(layer "B.Fab")
			(hide yes)
			(effects
				(font
					(size 1 1)
					(thickness 0.15)
				)
				(justify mirror)
			)
		)
		(property "Val" "10k"
			(at 0 0 270)
			(unlocked yes)
			(layer "B.Fab")
			(hide yes)
			(effects
				(font
					(size 1 1)
					(thickness 0.15)
				)
				(justify mirror)
			)
		)
		(property "License" "Apache-2.0"
			(at 0 0 270)
			(unlocked yes)
			(layer "B.Fab")
			(hide yes)
			(effects
				(font
					(size 1 1)
					(thickness 0.15)
				)
				(justify mirror)
			)
		)
		(property "Author" "Antmicro"
			(at 0 0 270)
			(unlocked yes)
			(layer "B.Fab")
			(hide yes)
			(effects
				(font
					(size 1 1)
					(thickness 0.15)
				)
				(justify mirror)
			)
		)
		(property "Tolerance" "1%"
			(at 0 0 270)
			(unlocked yes)
			(layer "B.Fab")
			(hide yes)
			(effects
				(font
					(size 1 1)
					(thickness 0.15)
				)
				(justify mirror)
			)
		)
		(sheetname "/Peripherals/")
		(sheetfile "peripherals.kicad_sch")
		(attr smd)
		(fp_poly
			(pts
				(xy -0.925 0.47) (xy -0.925 -0.47) (xy 0.925 -0.47) (xy 0.925 0.47)
			)
			(stroke
				(width 0.05)
				(type default)
			)
			(fill no)
			(layer "B.CrtYd")
		)
		(fp_poly
			(pts
				(xy -0.5 0.25) (xy -0.5 -0.25) (xy 0.5 -0.25) (xy 0.5 0.25)
			)
			(stroke
				(width 0.15)
				(type solid)
			)
			(fill no)
			(layer "B.Fab")
		)
		(fp_text user "License: Apache-2.0"
			(at -0.949999 -5.169 90)
			(layer "B.Fab")
			(effects
				(font
					(size 0.7 0.7)
					(thickness 0.15)
				)
				(justify right top mirror)
			)
		)
		(fp_text user "Author: Antmicro"
			(at -0.95 -4.169 90)
			(layer "B.Fab")
			(effects
				(font
					(size 0.7 0.7)
					(thickness 0.15)
				)
				(justify right top mirror)
			)
		)
		(fp_text user "${REFERENCE}"
			(at -0.95 -3.168 90)
			(layer "B.Fab")
			(effects
				(font
					(size 0.7 0.7)
					(thickness 0.15)
				)
				(justify right top mirror)
			)
		)
		(pad "1" smd roundrect
			(at -0.48 0 90)
			(size 0.59 0.64)
			(layers "B.Cu" "B.Mask" "B.Paste")
			(roundrect_rratio 0.25)
			(net 1 "GND")
			(pintype "passive")
		)
		(pad "2" smd roundrect
			(at 0.48 0 90)
			(size 0.59 0.64)
			(layers "B.Cu" "B.Mask" "B.Paste")
			(roundrect_rratio 0.25)
			(net 1010 "Net-(U55-ISET)")
			(pintype "passive")
		)
	)
	(footprint "antmicro-footprints:TP_SMD_0.75mm"
		(layer "B.Cu")
		(at 160 145 -90)
		(property "Reference" "TP90"
			(at -0.4 -1.5 90)
			(layer "B.SilkS")
			(effects
				(font
					(size 0.7 0.7)
					(thickness 0.15)
				)
				(justify left bottom mirror)
			)
		)
		(property "Value" "TP_0.75mm_SMD"
			(at 0 -1.2 90)
			(layer "B.Fab")
			(effects
				(font
					(size 0.7 0.7)
					(thickness 0.15)
				)
				(justify left bottom mirror)
			)
		)
		(property "Description" "SMT test point"
			(at 0 0 90)
			(layer "B.Fab")
			(hide yes)
			(effects
				(font
					(size 1.27 1.27)
					(thickness 0.15)
				)
				(justify mirror)
			)
		)
		(property "MPN" ""
			(at 0 0 90)
			(unlocked yes)
			(layer "B.Fab")
			(hide yes)
			(effects
				(font
					(size 1 1)
					(thickness 0.15)
				)
				(justify mirror)
			)
		)
		(property "Manufacturer" ""
			(at 0 0 90)
			(unlocked yes)
			(layer "B.Fab")
			(hide yes)
			(effects
				(font
					(size 1 1)
					(thickness 0.15)
				)
				(justify mirror)
			)
		)
		(property "Author" "Antmicro"
			(at 0 0 90)
			(unlocked yes)
			(layer "B.Fab")
			(hide yes)
			(effects
				(font
					(size 1 1)
					(thickness 0.15)
				)
				(justify mirror)
			)
		)
		(property "License" "Apache-2.0"
			(at 0 0 90)
			(unlocked yes)
			(layer "B.Fab")
			(hide yes)
			(effects
				(font
					(size 1 1)
					(thickness 0.15)
				)
				(justify mirror)
			)
		)
		(sheetname "/Peripherals/")
		(sheetfile "peripherals.kicad_sch")
		(attr exclude_from_pos_files exclude_from_bom)
		(fp_circle
			(center 0 0)
			(end 0.475 0)
			(stroke
				(width 0.05)
				(type default)
			)
			(fill no)
			(layer "B.CrtYd")
		)
		(fp_text user "License: Apache-2.0"
			(at -0.4 -5.101 90)
			(layer "B.Fab")
			(effects
				(font
					(size 0.7 0.7)
					(thickness 0.15)
				)
				(justify left bottom mirror)
			)
		)
		(fp_text user "${REFERENCE}"
			(at -0.4 -2.7 90)
			(layer "B.Fab")
			(effects
				(font
					(size 0.7 0.7)
					(thickness 0.15)
				)
				(justify left bottom mirror)
			)
		)
		(fp_text user "Author: Antmicro"
			(at -0.4 -3.901 90)
			(layer "B.Fab")
			(effects
				(font
					(size 0.7 0.7)
					(thickness 0.15)
				)
				(justify left bottom mirror)
			)
		)
		(pad "1" smd circle
			(at 0 0 270)
			(size 0.75 0.75)
			(layers "B.Cu" "B.Mask")
			(net 100 "/Peripherals/FAN_TACH")
			(pinfunction "1")
			(pintype "passive")
		)
	)
	(footprint "antmicro-footprints:TP_SMD_0.75mm"
		(layer "B.Cu")
		(at 233.8 116.3 180)
		(property "Reference" "TP43"
			(at 0 0.6 0)
			(layer "B.SilkS")
			(effects
				(font
					(size 0.7 0.7)
					(thickness 0.15)
				)
				(justify left bottom mirror)
			)
		)
		(property "Value" "TP_0.75mm_SMD"
			(at 0 -1.2 0)
			(layer "B.Fab")
			(effects
				(font
					(size 0.7 0.7)
					(thickness 0.15)
				)
				(justify left bottom mirror)
			)
		)
		(property "Description" "SMT test point"
			(at 0 0 0)
			(layer "B.Fab")
			(hide yes)
			(effects
				(font
					(size 1.27 1.27)
					(thickness 0.15)
				)
				(justify mirror)
			)
		)
		(property "MPN" ""
			(at 0 0 0)
			(unlocked yes)
			(layer "B.Fab")
			(hide yes)
			(effects
				(font
					(size 1 1)
					(thickness 0.15)
				)
				(justify mirror)
			)
		)
		(property "Manufacturer" ""
			(at 0 0 0)
			(unlocked yes)
			(layer "B.Fab")
			(hide yes)
			(effects
				(font
					(size 1 1)
					(thickness 0.15)
				)
				(justify mirror)
			)
		)
		(property "Author" "Antmicro"
			(at 0 0 0)
			(unlocked yes)
			(layer "B.Fab")
			(hide yes)
			(effects
				(font
					(size 1 1)
					(thickness 0.15)
				)
				(justify mirror)
			)
		)
		(property "License" "Apache-2.0"
			(at 0 0 0)
			(unlocked yes)
			(layer "B.Fab")
			(hide yes)
			(effects
				(font
					(size 1 1)
					(thickness 0.15)
				)
				(justify mirror)
			)
		)
		(sheetname "/USB Hub/")
		(sheetfile "usb_hub.kicad_sch")
		(attr exclude_from_pos_files exclude_from_bom)
		(fp_circle
			(center 0 0)
			(end 0.475 0)
			(stroke
				(width 0.05)
				(type default)
			)
			(fill no)
			(layer "B.CrtYd")
		)
		(fp_text user "License: Apache-2.0"
			(at -0.4 -5.101 0)
			(layer "B.Fab")
			(effects
				(font
					(size 0.7 0.7)
					(thickness 0.15)
				)
				(justify left bottom mirror)
			)
		)
		(fp_text user "Author: Antmicro"
			(at -0.4 -3.901 0)
			(layer "B.Fab")
			(effects
				(font
					(size 0.7 0.7)
					(thickness 0.15)
				)
				(justify left bottom mirror)
			)
		)
		(fp_text user "${REFERENCE}"
			(at -0.4 -2.7 0)
			(layer "B.Fab")
			(effects
				(font
					(size 0.7 0.7)
					(thickness 0.15)
				)
				(justify left bottom mirror)
			)
		)
		(pad "1" smd circle
			(at 0 0 180)
			(size 0.75 0.75)
			(layers "B.Cu" "B.Mask")
			(net 71 "/USB Hub/USBC3_VBUS")
			(pinfunction "1")
			(pintype "passive")
		)
	)
	(footprint "antmicro-footprints:R_0402_1005Metric"
		(layer "B.Cu")
		(at 212.8 88.775001)
		(descr "Resistor SMD 0402")
		(tags "resistor SMD 0402")
		(property "Reference" "R134"
			(at -3.9 -0.3 0)
			(layer "B.SilkS")
			(effects
				(font
					(size 0.7 0.7)
					(thickness 0.15)
				)
				(justify right top mirror)
			)
		)
		(property "Value" "R_1k_0402"
			(at -1.011843 -1.772046 0)
			(layer "B.Fab")
			(effects
				(font
					(size 0.7 0.7)
					(thickness 0.15)
				)
				(justify right top mirror)
			)
		)
		(property "Datasheet" "https://www.bourns.com/docs/product-datasheets/cr.pdf"
			(at 0 0 0)
			(layer "B.Fab")
			(hide yes)
			(effects
				(font
					(size 1.27 1.27)
					(thickness 0.15)
				)
				(justify mirror)
			)
		)
		(property "Description" "SMD Chip Resistor, 1 kohm, ± 1%, 63 mW, 0402 [1005 Metric], Thick Film, General Purpose"
			(at 0 0 0)
			(layer "B.Fab")
			(hide yes)
			(effects
				(font
					(size 1.27 1.27)
					(thickness 0.15)
				)
				(justify mirror)
			)
		)
		(property "Manufacturer" "Bourns"
			(at 0 0 180)
			(unlocked yes)
			(layer "B.Fab")
			(hide yes)
			(effects
				(font
					(size 1 1)
					(thickness 0.15)
				)
				(justify mirror)
			)
		)
		(property "MPN" "CR0402-FX-1001GLF"
			(at 0 0 180)
			(unlocked yes)
			(layer "B.Fab")
			(hide yes)
			(effects
				(font
					(size 1 1)
					(thickness 0.15)
				)
				(justify mirror)
			)
		)
		(property "Val" "1k"
			(at 0 0 180)
			(unlocked yes)
			(layer "B.Fab")
			(hide yes)
			(effects
				(font
					(size 1 1)
					(thickness 0.15)
				)
				(justify mirror)
			)
		)
		(property "License" "Apache-2.0"
			(at 0 0 180)
			(unlocked yes)
			(layer "B.Fab")
			(hide yes)
			(effects
				(font
					(size 1 1)
					(thickness 0.15)
				)
				(justify mirror)
			)
		)
		(property "Author" "Antmicro"
			(at 0 0 180)
			(unlocked yes)
			(layer "B.Fab")
			(hide yes)
			(effects
				(font
					(size 1 1)
					(thickness 0.15)
				)
				(justify mirror)
			)
		)
		(property "Tolerance" "1%"
			(at 0 0 180)
			(unlocked yes)
			(layer "B.Fab")
			(hide yes)
			(effects
				(font
					(size 1 1)
					(thickness 0.15)
				)
				(justify mirror)
			)
		)
		(sheetname "/USB DP Alt mode/")
		(sheetfile "usb_dp.kicad_sch")
		(attr smd exclude_from_pos_files exclude_from_bom dnp)
		(fp_poly
			(pts
				(xy -0.925 0.47) (xy 0.925 0.47) (xy 0.925 -0.47) (xy -0.925 -0.47)
			)
			(stroke
				(width 0.05)
				(type default)
			)
			(fill no)
			(layer "B.CrtYd")
		)
		(fp_poly
			(pts
				(xy -0.5 0.25) (xy 0.5 0.25) (xy 0.5 -0.25) (xy -0.5 -0.25)
			)
			(stroke
				(width 0.15)
				(type solid)
			)
			(fill no)
			(layer "B.Fab")
		)
		(fp_text user "${REFERENCE}"
			(at -0.95 -3.168 0)
			(layer "B.Fab")
			(effects
				(font
					(size 0.7 0.7)
					(thickness 0.15)
				)
				(justify right top mirror)
			)
		)
		(fp_text user "Author: Antmicro"
			(at -0.95 -4.169 0)
			(layer "B.Fab")
			(effects
				(font
					(size 0.7 0.7)
					(thickness 0.15)
				)
				(justify right top mirror)
			)
		)
		(fp_text user "License: Apache-2.0"
			(at -0.949999 -5.169 0)
			(layer "B.Fab")
			(effects
				(font
					(size 0.7 0.7)
					(thickness 0.15)
				)
				(justify right top mirror)
			)
		)
		(pad "1" smd roundrect
			(at -0.48 0)
			(size 0.59 0.64)
			(layers "B.Cu" "B.Mask" "B.Paste")
			(roundrect_rratio 0.25)
			(net 966 "/USB DP Alt mode/USBC1_DPEQ0")
			(pintype "passive")
		)
		(pad "2" smd roundrect
			(at 0.48 0)
			(size 0.59 0.64)
			(layers "B.Cu" "B.Mask" "B.Paste")
			(roundrect_rratio 0.25)
			(net 2 "+3V3")
			(pintype "passive")
		)
	)
)
